FILE_TYPE = MACRO_DRAWING;
SET COLOR_WIRE YELLOW;
SET COLOR_PROP ORANGE;
SET COLOR_DOT WHITE;
SET COLOR_ARC YELLOW;
SET COLOR_BODY GREEN;
SET COLOR_NOTE PURPLE;
SET PROP_DISPLAY VALUE;
SET PAGE_NUMBER P179;
FORCEADD QUANTA_TITLE_BLOCK_C..1
(0 0);
FORCEPROP 1 LAST CUSTOM_TXT_CDS <NAME_2>
J 0
(-3175 50);
FORCEPROP 1 LAST CUSTOM_TXT_CDS <NAME_1>
J 0
(-3175 175);
FORCEPROP 1 LAST CUSTOM_TXT_CDS <Q_NUMBER>
J 0
(-1403 103);
DISPLAY 1.212766 (-1403 103);
FORCEPROP 1 LAST CUSTOM_TXT_CDS <Q_PROJ>
J 0
(-2382 102);
DISPLAY 1.212766 (-2382 102);
FORCEPROP 1 LAST CUSTOM_TXT_CDS <Q_REV>
J 0
(-184 103);
DISPLAY 1.212766 (-184 103);
FORCEPROP 1 LAST CUSTOM_TXT_CDS <CON_LAST_MODIFIED>
J 0
(-1885 15);
DISPLAY 0.978723 (-1885 15);
FORCEPROP 1 LAST CUSTOM_TXT_CDS <CON_PAGE_NUM> OF <CON_TOTAL_PAGES>
J 0
(-446 18);
DISPLAY 0.978723 (-446 18);
FORCEPROP 1 LAST Q_TITLE Blank
J 0
(-9366 26);
DISPLAY 2.446809 (-9366 26);
PAINT GREEN (-9366 26);
FORCEPROP 2 LAST PAGE_BORDER TRUE
J 0
(-7890 5250);
DISPLAY 0.638298 (-7890 5250);
PAINT PINK (-7890 5250);
DISPLAY INVISIBLE (-7890 5250);
FORCEPROP 2 LAST CDS_LIB pure_quanta
J 0
(0 0);
DISPLAY INVISIBLE (0 0);
FORCEPROP 1 LAST CDS_LMAN_SYM_OUTLINE -9475,6775,100,-125
J 0
(0 0);
DISPLAY 0.468085 (0 0);
PAINT GREEN (0 0);
DISPLAY INVISIBLE (0 0);
FORCEPROP 2 LAST CDS_XR_PAGE_TITLE CR-204 : @T6G_MB_LIB.T6G(SCH_1):PAGE204
J 0
(-7890 5250);
DISPLAY 0.638298 (-7890 5250);
PAINT PINK (-7890 5250);
DISPLAY INVISIBLE (-7890 5250);
FORCEPROP 2 LAST CUSTOM_TXT_CDS <XR_PAGE_TITLE>
J 0
(-7890 5250);
DISPLAY 0.638298 (-7890 5250);
PAINT PINK (-7890 5250);
DISPLAY INVISIBLE (-7890 5250);
FORCEPROP 1 LAST COMMENT_BODY TRUE
J 0
(12 -13);
DISPLAY 0.978723 (12 -13);
PAINT GREEN (12 -13);
DISPLAY INVISIBLE (12 -13);
FORCEPROP 1 LAST Q_DEPT BU9
J 1
(-3763 49);
DISPLAY 1.957447 (-3763 49);
PAINT GREEN (-3763 49);
DISPLAY INVISIBLE (-3763 49);
FORCEPROP 0 LAST CDS_CON_LAST_MODIFIED Thu Aug 24 10:15:12 2023
J 0
(-1885 15);
DISPLAY INVISIBLE (-1885 15);
QUIT
